(kicad_pcb
	(version 20241229)
	(generator "pcbnew")
	(generator_version "9.0")
	(general
		(thickness 1.6642)
		(legacy_teardrops no)
	)
	(paper "A3")
	(title_block
		(title "PolarFire SoM")
		(date "2025-07-22")
		(rev "1.1.4")
		(company "Antmicro Ltd")
		(comment 1 "www.antmicro.com")
		(comment 9 "footprints 234-237 of 470")
	)
	(layers
		(0 "F.Cu" mixed)
		(4 "In1.Cu" power)
		(6 "In2.Cu" signal)
		(8 "In3.Cu" power)
		(10 "In4.Cu" signal)
		(12 "In5.Cu" power)
		(14 "In6.Cu" power)
		(16 "In7.Cu" signal)
		(18 "In8.Cu" power)
		(20 "In9.Cu" signal)
		(22 "In10.Cu" power)
		(24 "In11.Cu" signal)
		(26 "In12.Cu" signal)
		(2 "B.Cu" mixed)
		(9 "F.Adhes" user "F.Adhesive")
		(11 "B.Adhes" user "B.Adhesive")
		(13 "F.Paste" user)
		(15 "B.Paste" user)
		(5 "F.SilkS" user "F.Silkscreen")
		(7 "B.SilkS" user "B.Silkscreen")
		(1 "F.Mask" user)
		(3 "B.Mask" user)
		(17 "Dwgs.User" user "User.Drawings")
		(19 "Cmts.User" user "User.Comments")
		(21 "Eco1.User" user "User.Eco1")
		(23 "Eco2.User" user "User.Eco2")
		(25 "Edge.Cuts" user)
		(27 "Margin" user)
		(31 "F.CrtYd" user "F.Courtyard")
		(29 "B.CrtYd" user "B.Courtyard")
		(35 "F.Fab" user)
		(33 "B.Fab" user)
	)
	(footprint "antmicro-footprints:C_0402_1005Metric"
		(layer "B.Cu")
		(at 206.14 149.61 180)
		(descr "Capacitor SMD 0402")
		(tags "capacitor SMD 0402")
		(property "Reference" "C212"
			(at 0.8 -0.4 0)
			(layer "B.SilkS")
			(effects
				(font
					(size 0.7 0.7)
					(thickness 0.15)
				)
				(justify left bottom mirror)
			)
		)
		(property "Value" "C_100n_0402"
			(at -1.022927 -2.155213 0)
			(layer "B.Fab")
			(hide yes)
			(effects
				(font
					(size 0.7 0.7)
					(thickness 0.15)
				)
				(justify left bottom mirror)
			)
		)
		(property "Datasheet" "https://www.murata.com/products/productdetail?partno=GRM155R61H104KE14%23"
			(at 0 0 180)
			(layer "F.Fab")
			(hide yes)
			(effects
				(font
					(size 1.27 1.27)
					(thickness 0.15)
				)
			)
		)
		(property "Description" "SMD Multilayer Ceramic Capacitor, 0.1 µF, 50 V, 0402 [1005 Metric], ± 10%, X5R, GRM Series"
			(at 0 0 180)
			(layer "F.Fab")
			(hide yes)
			(effects
				(font
					(size 1.27 1.27)
					(thickness 0.15)
				)
			)
		)
		(property "Author" "Antmicro"
			(at 412.28 299.22 0)
			(layer "B.Fab")
			(hide yes)
			(effects
				(font
					(size 1 1)
					(thickness 0.15)
				)
				(justify mirror)
			)
		)
		(property "Dielectric" "X5R"
			(at 412.28 299.22 0)
			(layer "B.Fab")
			(hide yes)
			(effects
				(font
					(size 1 1)
					(thickness 0.15)
				)
				(justify mirror)
			)
		)
		(property "License" "Apache-2.0"
			(at 412.28 299.22 0)
			(layer "B.Fab")
			(hide yes)
			(effects
				(font
					(size 1 1)
					(thickness 0.15)
				)
				(justify mirror)
			)
		)
		(property "MPN" "GRM155R61H104KE14D"
			(at 412.28 299.22 0)
			(layer "B.Fab")
			(hide yes)
			(effects
				(font
					(size 1 1)
					(thickness 0.15)
				)
				(justify mirror)
			)
		)
		(property "Manufacturer" "Murata"
			(at 412.28 299.22 0)
			(layer "B.Fab")
			(hide yes)
			(effects
				(font
					(size 1 1)
					(thickness 0.15)
				)
				(justify mirror)
			)
		)
		(property "Public" ""
			(at 412.28 299.22 0)
			(layer "B.Fab")
			(hide yes)
			(effects
				(font
					(size 1 1)
					(thickness 0.15)
				)
				(justify mirror)
			)
		)
		(property "Val" "100n"
			(at 412.28 299.22 0)
			(layer "B.Fab")
			(hide yes)
			(effects
				(font
					(size 1 1)
					(thickness 0.15)
				)
				(justify mirror)
			)
		)
		(property "Voltage" "50V"
			(at 412.28 299.22 0)
			(layer "B.Fab")
			(hide yes)
			(effects
				(font
					(size 1 1)
					(thickness 0.15)
				)
				(justify mirror)
			)
		)
		(sheetname "/MIPI CrossLink/")
		(sheetfile "crosslink.kicad_sch")
		(attr smd)
		(fp_rect
			(start -0.925 0.47)
			(end 0.925 -0.47)
			(stroke
				(width 0.05)
				(type default)
			)
			(fill no)
			(layer "B.CrtYd")
		)
		(fp_line
			(start 0.504 0.25)
			(end 0.504 -0.248)
			(stroke
				(width 0.15)
				(type solid)
			)
			(layer "B.Fab")
		)
		(fp_line
			(start 0.504 -0.248)
			(end -0.494 -0.248)
			(stroke
				(width 0.15)
				(type solid)
			)
			(layer "B.Fab")
		)
		(fp_line
			(start -0.494 0.25)
			(end 0.504 0.25)
			(stroke
				(width 0.15)
				(type solid)
			)
			(layer "B.Fab")
		)
		(fp_line
			(start -0.494 -0.248)
			(end -0.494 0.25)
			(stroke
				(width 0.15)
				(type solid)
			)
			(layer "B.Fab")
		)
		(fp_text user "Author: Antmicro"
			(at -0.939 -3.399 0)
			(layer "B.Fab")
			(effects
				(font
					(size 0.7 0.7)
					(thickness 0.15)
				)
				(justify left bottom mirror)
			)
		)
		(fp_text user "License: Apache-2.0"
			(at -0.939 -5.799 0)
			(layer "B.Fab")
			(effects
				(font
					(size 0.7 0.7)
					(thickness 0.15)
				)
				(justify left bottom mirror)
			)
		)
		(fp_text user "${REFERENCE}"
			(at -0.939 -4.599 0)
			(layer "B.Fab")
			(effects
				(font
					(size 0.7 0.7)
					(thickness 0.15)
				)
				(justify left bottom mirror)
			)
		)
		(pad "1" smd roundrect
			(at -0.48 0 180)
			(size 0.59 0.64)
			(layers "B.Cu" "B.Mask" "B.Paste")
			(roundrect_rratio 0.25)
			(net 417 "GND")
			(pintype "passive")
		)
		(pad "2" smd roundrect
			(at 0.48 0 180)
			(size 0.59 0.64)
			(layers "B.Cu" "B.Mask" "B.Paste")
			(roundrect_rratio 0.25)
			(net 205 "/MIPI CrossLink/CL_VCCA_DPHY1")
			(pintype "passive")
		)
	)
	(footprint "antmicro-footprints:R_0402_1005Metric"
		(layer "B.Cu")
		(at 182.41 139.3 -90)
		(descr "Resistor SMD 0402")
		(tags "resistor SMD 0402")
		(property "Reference" "R97"
			(at -2.14 -1.94 225)
			(layer "B.SilkS")
			(effects
				(font
					(size 0.7 0.7)
					(thickness 0.15)
				)
				(justify left bottom mirror)
			)
		)
		(property "Value" "R_0R_0402"
			(at -1.011843 -1.772047 90)
			(layer "B.Fab")
			(hide yes)
			(effects
				(font
					(size 0.7 0.7)
					(thickness 0.15)
				)
				(justify left bottom mirror)
			)
		)
		(property "Datasheet" "https://industrial.panasonic.com/cdbs/www-data/pdf/RDA0000/AOA0000C301.pdf"
			(at 0 0 270)
			(layer "F.Fab")
			(hide yes)
			(effects
				(font
					(size 1.27 1.27)
					(thickness 0.15)
				)
			)
		)
		(property "Description" "SMD Chip Resistor, Jumper, 0 ohm, 100 mW, 0402 [1005 Metric], Thick Film, General Purpose"
			(at 0 0 270)
			(layer "F.Fab")
			(hide yes)
			(effects
				(font
					(size 1.27 1.27)
					(thickness 0.15)
				)
			)
		)
		(property "Author" "Antmicro"
			(at 43.11 321.71 0)
			(layer "B.Fab")
			(hide yes)
			(effects
				(font
					(size 1 1)
					(thickness 0.15)
				)
				(justify mirror)
			)
		)
		(property "Current" "1A"
			(at 43.11 321.71 0)
			(layer "B.Fab")
			(hide yes)
			(effects
				(font
					(size 1 1)
					(thickness 0.15)
				)
				(justify mirror)
			)
		)
		(property "License" "Apache-2.0"
			(at 43.11 321.71 0)
			(layer "B.Fab")
			(hide yes)
			(effects
				(font
					(size 1 1)
					(thickness 0.15)
				)
				(justify mirror)
			)
		)
		(property "MPN" "ERJ2GE0R00X"
			(at 43.11 321.71 0)
			(layer "B.Fab")
			(hide yes)
			(effects
				(font
					(size 1 1)
					(thickness 0.15)
				)
				(justify mirror)
			)
		)
		(property "Manufacturer" "Panasonic"
			(at 43.11 321.71 0)
			(layer "B.Fab")
			(hide yes)
			(effects
				(font
					(size 1 1)
					(thickness 0.15)
				)
				(justify mirror)
			)
		)
		(property "Public" ""
			(at 43.11 321.71 0)
			(layer "B.Fab")
			(hide yes)
			(effects
				(font
					(size 1 1)
					(thickness 0.15)
				)
				(justify mirror)
			)
		)
		(property "Tolerance" "~"
			(at 43.11 321.71 0)
			(layer "B.Fab")
			(hide yes)
			(effects
				(font
					(size 1 1)
					(thickness 0.15)
				)
				(justify mirror)
			)
		)
		(property "Val" "0R"
			(at 43.11 321.71 0)
			(layer "B.Fab")
			(hide yes)
			(effects
				(font
					(size 1 1)
					(thickness 0.15)
				)
				(justify mirror)
			)
		)
		(sheetname "/Supply/")
		(sheetfile "supply.kicad_sch")
		(attr smd)
		(fp_rect
			(start -0.925 0.47)
			(end 0.925 -0.47)
			(stroke
				(width 0.05)
				(type default)
			)
			(fill no)
			(layer "B.CrtYd")
		)
		(fp_rect
			(start -0.5 0.25)
			(end 0.5 -0.25)
			(stroke
				(width 0.15)
				(type solid)
			)
			(fill no)
			(layer "B.Fab")
		)
		(fp_text user "${REFERENCE}"
			(at -0.95 -3.168 90)
			(layer "B.Fab")
			(effects
				(font
					(size 0.7 0.7)
					(thickness 0.15)
				)
				(justify left bottom mirror)
			)
		)
		(fp_text user "Author: Antmicro"
			(at -0.95 -4.169 90)
			(layer "B.Fab")
			(effects
				(font
					(size 0.7 0.7)
					(thickness 0.15)
				)
				(justify left bottom mirror)
			)
		)
		(fp_text user "License: Apache-2.0"
			(at -0.95 -5.169 90)
			(layer "B.Fab")
			(effects
				(font
					(size 0.7 0.7)
					(thickness 0.15)
				)
				(justify left bottom mirror)
			)
		)
		(pad "1" smd roundrect
			(at -0.48 0 270)
			(size 0.59 0.64)
			(layers "B.Cu" "B.Mask" "B.Paste")
			(roundrect_rratio 0.25)
			(net 272 "/Supply/SENSE3_P")
			(pintype "passive")
		)
		(pad "2" smd roundrect
			(at 0.48 0 270)
			(size 0.59 0.64)
			(layers "B.Cu" "B.Mask" "B.Paste")
			(roundrect_rratio 0.25)
			(net 578 "Net-(U6-SENSE3+)")
			(pintype "passive")
		)
	)
	(footprint "antmicro-footprints:C_0402_1005Metric"
		(layer "B.Cu")
		(at 180.025 136.45 90)
		(descr "Capacitor SMD 0402")
		(tags "capacitor SMD 0402")
		(property "Reference" "C76"
			(at -0.975 1.435 90)
			(layer "B.SilkS")
			(effects
				(font
					(size 0.7 0.7)
					(thickness 0.15)
				)
				(justify right bottom mirror)
			)
		)
		(property "Value" "C_10u_0402"
			(at -1.022927 -2.155213 90)
			(layer "B.Fab")
			(hide yes)
			(effects
				(font
					(size 0.7 0.7)
					(thickness 0.15)
				)
				(justify right bottom mirror)
			)
		)
		(property "Datasheet" "https://www.yageo.com/en/Chart/Download/pdf/CC0402MRX5R5BB106"
			(at 0 0 90)
			(layer "F.Fab")
			(hide yes)
			(effects
				(font
					(size 1.27 1.27)
					(thickness 0.15)
				)
			)
		)
		(property "Description" "SMD Multilayer Ceramic Capacitor, 10 µF, 6.3 V, 0402 [1005 Metric], ± 20%, X5R, CC Series"
			(at 0 0 90)
			(layer "F.Fab")
			(hide yes)
			(effects
				(font
					(size 1.27 1.27)
					(thickness 0.15)
				)
			)
		)
		(property "Author" "Antmicro"
			(at 316.475 -43.575 0)
			(layer "B.Fab")
			(hide yes)
			(effects
				(font
					(size 1 1)
					(thickness 0.15)
				)
				(justify mirror)
			)
		)
		(property "Dielectric" ""
			(at 316.475 -43.575 0)
			(layer "B.Fab")
			(hide yes)
			(effects
				(font
					(size 1 1)
					(thickness 0.15)
				)
				(justify mirror)
			)
		)
		(property "License" "Apache-2.0"
			(at 316.475 -43.575 0)
			(layer "B.Fab")
			(hide yes)
			(effects
				(font
					(size 1 1)
					(thickness 0.15)
				)
				(justify mirror)
			)
		)
		(property "MPN" "CC0402MRX5R5BB106"
			(at 316.475 -43.575 0)
			(layer "B.Fab")
			(hide yes)
			(effects
				(font
					(size 1 1)
					(thickness 0.15)
				)
				(justify mirror)
			)
		)
		(property "Manufacturer" "YAGEO"
			(at 316.475 -43.575 0)
			(layer "B.Fab")
			(hide yes)
			(effects
				(font
					(size 1 1)
					(thickness 0.15)
				)
				(justify mirror)
			)
		)
		(property "Public" ""
			(at 316.475 -43.575 0)
			(layer "B.Fab")
			(hide yes)
			(effects
				(font
					(size 1 1)
					(thickness 0.15)
				)
				(justify mirror)
			)
		)
		(property "Val" "10u"
			(at 316.475 -43.575 0)
			(layer "B.Fab")
			(hide yes)
			(effects
				(font
					(size 1 1)
					(thickness 0.15)
				)
				(justify mirror)
			)
		)
		(property "Voltage" ""
			(at 316.475 -43.575 0)
			(layer "B.Fab")
			(hide yes)
			(effects
				(font
					(size 1 1)
					(thickness 0.15)
				)
				(justify mirror)
			)
		)
		(sheetname "/LPDDR4/")
		(sheetfile "lpddr.kicad_sch")
		(attr smd)
		(fp_rect
			(start -0.925 0.47)
			(end 0.925 -0.47)
			(stroke
				(width 0.05)
				(type default)
			)
			(fill no)
			(layer "B.CrtYd")
		)
		(fp_line
			(start 0.504 -0.248)
			(end -0.494 -0.248)
			(stroke
				(width 0.15)
				(type solid)
			)
			(layer "B.Fab")
		)
		(fp_line
			(start -0.494 -0.248)
			(end -0.494 0.25)
			(stroke
				(width 0.15)
				(type solid)
			)
			(layer "B.Fab")
		)
		(fp_line
			(start 0.504 0.25)
			(end 0.504 -0.248)
			(stroke
				(width 0.15)
				(type solid)
			)
			(layer "B.Fab")
		)
		(fp_line
			(start -0.494 0.25)
			(end 0.504 0.25)
			(stroke
				(width 0.15)
				(type solid)
			)
			(layer "B.Fab")
		)
		(fp_text user "License: Apache-2.0"
			(at -0.939 -5.799 270)
			(layer "B.Fab")
			(effects
				(font
					(size 0.7 0.7)
					(thickness 0.15)
				)
				(justify left bottom mirror)
			)
		)
		(fp_text user "${REFERENCE}"
			(at -0.939 -4.599 270)
			(layer "B.Fab")
			(effects
				(font
					(size 0.7 0.7)
					(thickness 0.15)
				)
				(justify left bottom mirror)
			)
		)
		(fp_text user "Author: Antmicro"
			(at -0.939 -3.399 270)
			(layer "B.Fab")
			(effects
				(font
					(size 0.7 0.7)
					(thickness 0.15)
				)
				(justify left bottom mirror)
			)
		)
		(pad "1" smd roundrect
			(at -0.48 0 90)
			(size 0.59 0.64)
			(layers "B.Cu" "B.Mask" "B.Paste")
			(roundrect_rratio 0.25)
			(net 417 "GND")
			(pintype "passive")
		)
		(pad "2" smd roundrect
			(at 0.48 0 90)
			(size 0.59 0.64)
			(layers "B.Cu" "B.Mask" "B.Paste")
			(roundrect_rratio 0.25)
			(net 2 "+1V1")
			(pintype "passive")
		)
	)
	(footprint "antmicro-footprints:R_0402_1005Metric"
		(layer "B.Cu")
		(at 201.5 123.6 180)
		(descr "Resistor SMD 0402")
		(tags "resistor SMD 0402")
		(property "Reference" "R106"
			(at -4.73 -0.9 0)
			(layer "B.SilkS")
			(effects
				(font
					(size 0.7 0.7)
					(thickness 0.15)
				)
				(justify left bottom mirror)
			)
		)
		(property "Value" "R_4k7_0402"
			(at -1.011843 -1.772047 0)
			(layer "B.Fab")
			(hide yes)
			(effects
				(font
					(size 0.7 0.7)
					(thickness 0.15)
				)
				(justify left bottom mirror)
			)
		)
		(property "Datasheet" "https://www.bourns.com/docs/product-datasheets/cr.pdf"
			(at 0 0 180)
			(layer "F.Fab")
			(hide yes)
			(effects
				(font
					(size 1.27 1.27)
					(thickness 0.15)
				)
			)
		)
		(property "Description" "SMD Chip Resistor, 4.7 kohm, ± 1%, 62.5 mW, 0402 [1005 Metric], Thick Film, General Purpose"
			(at 0 0 180)
			(layer "F.Fab")
			(hide yes)
			(effects
				(font
					(size 1.27 1.27)
					(thickness 0.15)
				)
			)
		)
		(property "Author" "Antmicro"
			(at 403 247.2 0)
			(layer "B.Fab")
			(hide yes)
			(effects
				(font
					(size 1 1)
					(thickness 0.15)
				)
				(justify mirror)
			)
		)
		(property "License" "Apache-2.0"
			(at 403 247.2 0)
			(layer "B.Fab")
			(hide yes)
			(effects
				(font
					(size 1 1)
					(thickness 0.15)
				)
				(justify mirror)
			)
		)
		(property "MPN" "CR0402-FX-4701GLF"
			(at 403 247.2 0)
			(layer "B.Fab")
			(hide yes)
			(effects
				(font
					(size 1 1)
					(thickness 0.15)
				)
				(justify mirror)
			)
		)
		(property "Manufacturer" "Bourns"
			(at 403 247.2 0)
			(layer "B.Fab")
			(hide yes)
			(effects
				(font
					(size 1 1)
					(thickness 0.15)
				)
				(justify mirror)
			)
		)
		(property "Public" ""
			(at 403 247.2 0)
			(layer "B.Fab")
			(hide yes)
			(effects
				(font
					(size 1 1)
					(thickness 0.15)
				)
				(justify mirror)
			)
		)
		(property "Tolerance" "1%"
			(at 403 247.2 0)
			(layer "B.Fab")
			(hide yes)
			(effects
				(font
					(size 1 1)
					(thickness 0.15)
				)
				(justify mirror)
			)
		)
		(property "Val" "4k7"
			(at 403 247.2 0)
			(layer "B.Fab")
			(hide yes)
			(effects
				(font
					(size 1 1)
					(thickness 0.15)
				)
				(justify mirror)
			)
		)
		(sheetname "/FPGA MSSIO/")
		(sheetfile "fpga-mssio.kicad_sch")
		(attr smd)
		(fp_rect
			(start -0.925 0.47)
			(end 0.925 -0.47)
			(stroke
				(width 0.05)
				(type default)
			)
			(fill no)
			(layer "B.CrtYd")
		)
		(fp_rect
			(start -0.5 0.25)
			(end 0.5 -0.25)
			(stroke
				(width 0.15)
				(type solid)
			)
			(fill no)
			(layer "B.Fab")
		)
		(fp_text user "License: Apache-2.0"
			(at -0.95 -5.169 0)
			(layer "B.Fab")
			(effects
				(font
					(size 0.7 0.7)
					(thickness 0.15)
				)
				(justify left bottom mirror)
			)
		)
		(fp_text user "${REFERENCE}"
			(at -0.95 -3.168 0)
			(layer "B.Fab")
			(effects
				(font
					(size 0.7 0.7)
					(thickness 0.15)
				)
				(justify left bottom mirror)
			)
		)
		(fp_text user "Author: Antmicro"
			(at -0.95 -4.169 0)
			(layer "B.Fab")
			(effects
				(font
					(size 0.7 0.7)
					(thickness 0.15)
				)
				(justify left bottom mirror)
			)
		)
		(pad "1" smd roundrect
			(at -0.48 0 180)
			(size 0.59 0.64)
			(layers "B.Cu" "B.Mask" "B.Paste")
			(roundrect_rratio 0.25)
			(net 100 "/FPGA MSSIO/SUPPLY.SDA")
			(pintype "passive")
		)
		(pad "2" smd roundrect
			(at 0.48 0 180)
			(size 0.59 0.64)
			(layers "B.Cu" "B.Mask" "B.Paste")
			(roundrect_rratio 0.25)
			(net 649 "VDD")
			(pintype "passive")
		)
	)
)
